(kicad_pcb
	(version 20241229)
	(generator "pcbnew")
	(generator_version "9.0")
	(general
		(thickness 1.61)
		(legacy_teardrops no)
	)
	(paper "A3")
	(title_block
		(title "SO-DIMM DDR5 Tester")
		(date "2025-11-26")
		(rev "1.3.0")
		(comment 9 "footprint 147 of 627 (J2), pads 88-172 of 266")
	)
	(layers
		(0 "F.Cu" signal)
		(4 "In1.Cu" power)
		(6 "In2.Cu" mixed)
		(8 "In3.Cu" power)
		(10 "In4.Cu" mixed)
		(12 "In5.Cu" power)
		(14 "In6.Cu" mixed)
		(16 "In7.Cu" power)
		(18 "In8.Cu" power)
		(20 "In9.Cu" mixed)
		(22 "In10.Cu" power)
		(2 "B.Cu" signal)
		(9 "F.Adhes" user "F.Adhesive")
		(11 "B.Adhes" user "B.Adhesive")
		(13 "F.Paste" user)
		(15 "B.Paste" user)
		(5 "F.SilkS" user "F.Silkscreen")
		(7 "B.SilkS" user "B.Silkscreen")
		(1 "F.Mask" user)
		(3 "B.Mask" user)
		(17 "Dwgs.User" user "User.Drawings")
		(19 "Cmts.User" user "User.Comments")
		(21 "Eco1.User" user "User.Eco1")
		(23 "Eco2.User" user "User.Eco2")
		(25 "Edge.Cuts" user)
		(27 "Margin" user)
		(31 "F.CrtYd" user "F.Courtyard")
		(29 "B.CrtYd" user "B.Courtyard")
		(35 "F.Fab" user)
		(33 "B.Fab" user)
	)
	(footprint "antmicro-footprints:Bus_DDR5_SODIMM_Amphenol_10161033-002RHLF"
		(layer "F.Cu")
		(at 139.780001 134.8375 180)
		(property "Reference" "J2"
			(at -35.119999 -13.0625 180)
			(layer "F.SilkS")
			(effects
				(font
					(size 0.7 0.7)
					(thickness 0.15)
				)
				(justify left bottom)
			)
		)
		(property "Value" "Bus_DDR5_SODIMM_Amphenol_10161033-002RHLF_CUSTOM_2xDetectPin"
			(at 0 13.5 180)
			(layer "F.Fab")
			(effects
				(font
					(size 0.7 0.7)
					(thickness 0.15)
				)
				(justify left bottom)
			)
		)
		(property "Datasheet" "https://cdn.amphenol-cs.com/media/wysiwyg/files/documentation/datasheet/ssio/ssio_ddr5_sodimm.pdf"
			(at 0 0 180)
			(layer "F.Fab")
			(hide yes)
			(effects
				(font
					(size 1.27 1.27)
					(thickness 0.15)
				)
			)
		)
		(property "Author" "Antmicro"
			(at 279.560002 269.675 0)
			(layer "F.Fab")
			(hide yes)
			(effects
				(font
					(size 1 1)
					(thickness 0.15)
				)
			)
		)
		(property "License" "Apache-2.0"
			(at 279.560002 269.675 0)
			(layer "F.Fab")
			(hide yes)
			(effects
				(font
					(size 1 1)
					(thickness 0.15)
				)
			)
		)
		(property "MPN" "10161033-002RHLF"
			(at 279.560002 269.675 0)
			(layer "F.Fab")
			(hide yes)
			(effects
				(font
					(size 1 1)
					(thickness 0.15)
				)
			)
		)
		(property "Manufacturer" "Amphenol"
			(at 279.560002 269.675 0)
			(layer "F.Fab")
			(hide yes)
			(effects
				(font
					(size 1 1)
					(thickness 0.15)
				)
			)
		)
		(sheetname "/DDR5 SODIMM/")
		(sheetfile "ddr5-sodimm.kicad_sch")
		(attr smd)
		(pad "86" smd rect
			(at 12.13 -3.965 180)
			(size 0.3 1.5)
			(layers "F.Cu" "F.Mask" "F.Paste")
			(net 1 "GND")
			(pinfunction "VSS")
			(pintype "passive")
		)
		(pad "87" smd rect
			(at 11.88 -11.365 180)
			(size 0.3 1.5)
			(layers "F.Cu" "F.Mask" "F.Paste")
			(net 110 "/DDR5 SODIMM/A.DQ28")
			(pinfunction "DQ28_A")
			(pintype "passive")
		)
		(pad "88" smd rect
			(at 11.63 -3.965 180)
			(size 0.3 1.5)
			(layers "F.Cu" "F.Mask" "F.Paste")
			(net 111 "/DDR5 SODIMM/A.DQ29")
			(pinfunction "DQ29_A")
			(pintype "passive")
		)
		(pad "89" smd rect
			(at 11.38 -11.365 180)
			(size 0.3 1.5)
			(layers "F.Cu" "F.Mask" "F.Paste")
			(net 1 "GND")
			(pinfunction "VSS")
			(pintype "passive")
		)
		(pad "90" smd rect
			(at 11.13 -3.965 180)
			(size 0.3 1.5)
			(layers "F.Cu" "F.Mask" "F.Paste")
			(net 1 "GND")
			(pinfunction "VSS")
			(pintype "passive")
		)
		(pad "91" smd rect
			(at 10.88 -11.365 180)
			(size 0.3 1.5)
			(layers "F.Cu" "F.Mask" "F.Paste")
			(net 112 "/DDR5 SODIMM/A.DQ30")
			(pinfunction "DQ30_A")
			(pintype "passive")
		)
		(pad "92" smd rect
			(at 10.63 -3.965 180)
			(size 0.3 1.5)
			(layers "F.Cu" "F.Mask" "F.Paste")
			(net 113 "/DDR5 SODIMM/A.DQ31")
			(pinfunction "DQ31_A")
			(pintype "passive")
		)
		(pad "93" smd rect
			(at 10.38 -11.365 180)
			(size 0.3 1.5)
			(layers "F.Cu" "F.Mask" "F.Paste")
			(net 1 "GND")
			(pinfunction "VSS")
			(pintype "passive")
		)
		(pad "94" smd rect
			(at 10.13 -3.965 180)
			(size 0.3 1.5)
			(layers "F.Cu" "F.Mask" "F.Paste")
			(net 1 "GND")
			(pinfunction "VSS")
			(pintype "passive")
		)
		(pad "95" smd rect
			(at 9.88 -11.365 180)
			(size 0.3 1.5)
			(layers "F.Cu" "F.Mask" "F.Paste")
			(net 114 "/DDR5 SODIMM/A.CB0")
			(pinfunction "CB0_A")
			(pintype "passive")
		)
		(pad "96" smd rect
			(at 9.63 -3.965 180)
			(size 0.3 1.5)
			(layers "F.Cu" "F.Mask" "F.Paste")
			(net 115 "/DDR5 SODIMM/A.CB1")
			(pinfunction "CB1_A")
			(pintype "passive")
		)
		(pad "97" smd rect
			(at 9.38 -11.365 180)
			(size 0.3 1.5)
			(layers "F.Cu" "F.Mask" "F.Paste")
			(net 1 "GND")
			(pinfunction "VSS")
			(pintype "passive")
		)
		(pad "98" smd rect
			(at 9.13 -3.965 180)
			(size 0.3 1.5)
			(layers "F.Cu" "F.Mask" "F.Paste")
			(net 1 "GND")
			(pinfunction "VSS")
			(pintype "passive")
		)
		(pad "99" smd rect
			(at 8.88 -11.365 180)
			(size 0.3 1.5)
			(layers "F.Cu" "F.Mask" "F.Paste")
			(net 116 "/DDR5 SODIMM/A.CB2")
			(pinfunction "CB2_A")
			(pintype "passive")
		)
		(pad "100" smd rect
			(at 8.63 -3.965 180)
			(size 0.3 1.5)
			(layers "F.Cu" "F.Mask" "F.Paste")
			(net 117 "/DDR5 SODIMM/A.DQS4_N")
			(pinfunction "DQS4_A_c")
			(pintype "passive")
		)
		(pad "101" smd rect
			(at 8.38 -11.365 180)
			(size 0.3 1.5)
			(layers "F.Cu" "F.Mask" "F.Paste")
			(net 1 "GND")
			(pinfunction "VSS")
			(pintype "passive")
		)
		(pad "102" smd rect
			(at 8.13 -3.965 180)
			(size 0.3 1.5)
			(layers "F.Cu" "F.Mask" "F.Paste")
			(net 118 "/DDR5 SODIMM/A.DQS4_P")
			(pinfunction "DQS4_A_t")
			(pintype "passive")
		)
		(pad "103" smd rect
			(at 7.88 -11.365 180)
			(size 0.3 1.5)
			(layers "F.Cu" "F.Mask" "F.Paste")
			(net 119 "/DDR5 SODIMM/A.CB3")
			(pinfunction "CB3_A")
			(pintype "passive")
		)
		(pad "104" smd rect
			(at 7.63 -3.965 180)
			(size 0.3 1.5)
			(layers "F.Cu" "F.Mask" "F.Paste")
			(net 1 "GND")
			(pinfunction "VSS")
			(pintype "passive")
		)
		(pad "105" smd rect
			(at 7.38 -11.365 180)
			(size 0.3 1.5)
			(layers "F.Cu" "F.Mask" "F.Paste")
			(net 1 "GND")
			(pinfunction "VSS")
			(pintype "passive")
		)
		(pad "106" smd rect
			(at 7.13 -3.965 180)
			(size 0.3 1.5)
			(layers "F.Cu" "F.Mask" "F.Paste")
			(net 120 "/DDR5 SODIMM/A.~{CS0}")
			(pinfunction "CS0_A_n")
			(pintype "passive")
		)
		(pad "107" smd rect
			(at 6.88 -11.365 180)
			(size 0.3 1.5)
			(layers "F.Cu" "F.Mask" "F.Paste")
			(net 121 "/DDR5 SODIMM/A.CA0")
			(pinfunction "CA0_A")
			(pintype "passive")
		)
		(pad "108" smd rect
			(at 6.63 -3.965 180)
			(size 0.3 1.5)
			(layers "F.Cu" "F.Mask" "F.Paste")
			(net 122 "/DDR5 SODIMM/Control.~{ALERT}")
			(pinfunction "ALERT_n")
			(pintype "passive")
		)
		(pad "109" smd rect
			(at 6.38 -11.365 180)
			(size 0.3 1.5)
			(layers "F.Cu" "F.Mask" "F.Paste")
			(net 136 "/DDR5 SODIMM/A.CA1")
			(pinfunction "CA1_A")
			(pintype "passive")
		)
		(pad "110" smd rect
			(at 6.13 -3.965 180)
			(size 0.3 1.5)
			(layers "F.Cu" "F.Mask" "F.Paste")
			(net 138 "/DDR5 SODIMM/A.~{CS1}")
			(pinfunction "CS1_A_n")
			(pintype "passive")
		)
		(pad "111" smd rect
			(at 5.88 -11.365 180)
			(size 0.3 1.5)
			(layers "F.Cu" "F.Mask" "F.Paste")
			(net 1 "GND")
			(pinfunction "VSS")
			(pintype "passive")
		)
		(pad "112" smd rect
			(at 5.63 -3.965 180)
			(size 0.3 1.5)
			(layers "F.Cu" "F.Mask" "F.Paste")
			(net 1 "GND")
			(pinfunction "VSS")
			(pintype "passive")
		)
		(pad "113" smd rect
			(at 5.38 -11.365 180)
			(size 0.3 1.5)
			(layers "F.Cu" "F.Mask" "F.Paste")
			(net 139 "/DDR5 SODIMM/A.CA2")
			(pinfunction "CA2_A")
			(pintype "passive")
		)
		(pad "114" smd rect
			(at 5.13 -3.965 180)
			(size 0.3 1.5)
			(layers "F.Cu" "F.Mask" "F.Paste")
			(net 147 "/DDR5 SODIMM/A.CA3")
			(pinfunction "CA3_A")
			(pintype "passive")
		)
		(pad "115" smd rect
			(at 4.88 -11.365 180)
			(size 0.3 1.5)
			(layers "F.Cu" "F.Mask" "F.Paste")
			(net 148 "/DDR5 SODIMM/A.CA4")
			(pinfunction "CA4_A")
			(pintype "passive")
		)
		(pad "116" smd rect
			(at 4.63 -3.965 180)
			(size 0.3 1.5)
			(layers "F.Cu" "F.Mask" "F.Paste")
			(net 149 "/DDR5 SODIMM/A.CA5")
			(pinfunction "CA5_A")
			(pintype "passive")
		)
		(pad "117" smd rect
			(at 4.38 -11.365 180)
			(size 0.3 1.5)
			(layers "F.Cu" "F.Mask" "F.Paste")
			(net 1 "GND")
			(pinfunction "VSS")
			(pintype "passive")
		)
		(pad "118" smd rect
			(at 4.13 -3.965 180)
			(size 0.3 1.5)
			(layers "F.Cu" "F.Mask" "F.Paste")
			(net 1 "GND")
			(pinfunction "VSS")
			(pintype "passive")
		)
		(pad "119" smd rect
			(at 3.88 -11.365 180)
			(size 0.3 1.5)
			(layers "F.Cu" "F.Mask" "F.Paste")
			(net 150 "/DDR5 SODIMM/A.CA6")
			(pinfunction "CA6_A")
			(pintype "passive")
		)
		(pad "120" smd rect
			(at 3.63 -3.965 180)
			(size 0.3 1.5)
			(layers "F.Cu" "F.Mask" "F.Paste")
			(net 151 "/DDR5 SODIMM/A.CA7")
			(pinfunction "CA7_A")
			(pintype "passive")
		)
		(pad "121" smd rect
			(at 3.38 -11.365 180)
			(size 0.3 1.5)
			(layers "F.Cu" "F.Mask" "F.Paste")
			(net 152 "/DDR5 SODIMM/A.CA8")
			(pinfunction "CA8_A")
			(pintype "passive")
		)
		(pad "122" smd rect
			(at 3.13 -3.965 180)
			(size 0.3 1.5)
			(layers "F.Cu" "F.Mask" "F.Paste")
			(net 153 "/DDR5 SODIMM/A.CA9")
			(pinfunction "CA9_A")
			(pintype "passive")
		)
		(pad "123" smd rect
			(at 2.88 -11.365 180)
			(size 0.3 1.5)
			(layers "F.Cu" "F.Mask" "F.Paste")
			(net 1 "GND")
			(pinfunction "VSS")
			(pintype "passive")
		)
		(pad "124" smd rect
			(at 2.63 -3.965 180)
			(size 0.3 1.5)
			(layers "F.Cu" "F.Mask" "F.Paste")
			(net 140 "/DDR5 SODIMM/VSS_DET1")
			(pinfunction "SDM_DETECT")
			(pintype "passive")
		)
		(pad "125" smd rect
			(at 2.38 -11.365 180)
			(size 0.3 1.5)
			(layers "F.Cu" "F.Mask" "F.Paste")
			(net 154 "/DDR5 SODIMM/A.CA10")
			(pinfunction "CA10_A")
			(pintype "passive")
		)
		(pad "126" smd rect
			(at 2.13 -3.965 180)
			(size 0.3 1.5)
			(layers "F.Cu" "F.Mask" "F.Paste")
			(net 155 "/DDR5 SODIMM/A.CA11")
			(pinfunction "CA11_A")
			(pintype "passive")
		)
		(pad "127" smd rect
			(at 0.38 -11.365 180)
			(size 0.3 1.5)
			(layers "F.Cu" "F.Mask" "F.Paste")
			(net 156 "/DDR5 SODIMM/A.CA12")
			(pinfunction "CA12_A")
			(pintype "passive")
		)
		(pad "128" smd rect
			(at 0.13 -3.965 180)
			(size 0.3 1.5)
			(layers "F.Cu" "F.Mask" "F.Paste")
			(net 171 "/DDR5 SODIMM/RFU2")
			(pinfunction "RFU")
			(pintype "passive")
		)
		(pad "129" smd rect
			(at -0.12 -11.365 180)
			(size 0.3 1.5)
			(layers "F.Cu" "F.Mask" "F.Paste")
			(net 1 "GND")
			(pinfunction "VSS")
			(pintype "passive")
		)
		(pad "130" smd rect
			(at -0.37 -3.965 180)
			(size 0.3 1.5)
			(layers "F.Cu" "F.Mask" "F.Paste")
			(net 172 "/DDR5 SODIMM/VSS_DET2")
			(pinfunction "TB_DETECT")
			(pintype "passive")
		)
		(pad "131" smd rect
			(at -0.62 -11.365 180)
			(size 0.3 1.5)
			(layers "F.Cu" "F.Mask" "F.Paste")
			(net 157 "/DDR5 SODIMM/A.CK0_P")
			(pinfunction "CK0_A_t")
			(pintype "passive")
		)
		(pad "132" smd rect
			(at -0.87 -3.965 180)
			(size 0.3 1.5)
			(layers "F.Cu" "F.Mask" "F.Paste")
			(net 158 "/DDR5 SODIMM/A.CK1_P")
			(pinfunction "CK1_A_t")
			(pintype "passive")
		)
		(pad "133" smd rect
			(at -1.12 -11.365 180)
			(size 0.3 1.5)
			(layers "F.Cu" "F.Mask" "F.Paste")
			(net 159 "/DDR5 SODIMM/A.CK0_N")
			(pinfunction "CK0_A_c")
			(pintype "passive")
		)
		(pad "134" smd rect
			(at -1.37 -3.965 180)
			(size 0.3 1.5)
			(layers "F.Cu" "F.Mask" "F.Paste")
			(net 160 "/DDR5 SODIMM/A.CK1_N")
			(pinfunction "CK1_A_c")
			(pintype "passive")
		)
		(pad "135" smd rect
			(at -1.62 -11.365 180)
			(size 0.3 1.5)
			(layers "F.Cu" "F.Mask" "F.Paste")
			(net 1 "GND")
			(pinfunction "VSS")
			(pintype "passive")
		)
		(pad "136" smd rect
			(at -1.87 -3.965 180)
			(size 0.3 1.5)
			(layers "F.Cu" "F.Mask" "F.Paste")
			(net 1 "GND")
			(pinfunction "VSS")
			(pintype "passive")
		)
		(pad "137" smd rect
			(at -2.12 -11.365 180)
			(size 0.3 1.5)
			(layers "F.Cu" "F.Mask" "F.Paste")
			(net 161 "/DDR5 SODIMM/B.CK0_P")
			(pinfunction "CK0_B_t")
			(pintype "passive")
		)
		(pad "138" smd rect
			(at -2.37 -3.965 180)
			(size 0.3 1.5)
			(layers "F.Cu" "F.Mask" "F.Paste")
			(net 162 "/DDR5 SODIMM/B.CK1_P")
			(pinfunction "CK1_B_t")
			(pintype "passive")
		)
		(pad "139" smd rect
			(at -2.62 -11.365 180)
			(size 0.3 1.5)
			(layers "F.Cu" "F.Mask" "F.Paste")
			(net 163 "/DDR5 SODIMM/B.CK0_N")
			(pinfunction "CK0_B_c")
			(pintype "passive")
		)
		(pad "140" smd rect
			(at -2.87 -3.965 180)
			(size 0.3 1.5)
			(layers "F.Cu" "F.Mask" "F.Paste")
			(net 164 "/DDR5 SODIMM/B.CK1_N")
			(pinfunction "CK1_B_C")
			(pintype "passive")
		)
		(pad "141" smd rect
			(at -3.12 -11.365 180)
			(size 0.3 1.5)
			(layers "F.Cu" "F.Mask" "F.Paste")
			(net 1 "GND")
			(pinfunction "VSS")
			(pintype "passive")
		)
		(pad "142" smd rect
			(at -3.37 -3.965 180)
			(size 0.3 1.5)
			(layers "F.Cu" "F.Mask" "F.Paste")
			(net 1 "GND")
			(pinfunction "VSS")
			(pintype "passive")
		)
		(pad "143" smd rect
			(at -3.62 -11.365 180)
			(size 0.3 1.5)
			(layers "F.Cu" "F.Mask" "F.Paste")
			(net 173 "/DDR5 SODIMM/RFU3")
			(pinfunction "RFU")
			(pintype "passive")
		)
		(pad "144" smd rect
			(at -3.87 -3.965 180)
			(size 0.3 1.5)
			(layers "F.Cu" "F.Mask" "F.Paste")
			(net 165 "/DDR5 SODIMM/B.CA12")
			(pinfunction "CA12_B")
			(pintype "passive")
		)
		(pad "145" smd rect
			(at -4.12 -11.365 180)
			(size 0.3 1.5)
			(layers "F.Cu" "F.Mask" "F.Paste")
			(net 166 "/DDR5 SODIMM/B.CA11")
			(pinfunction "CA11_B")
			(pintype "passive")
		)
		(pad "146" smd rect
			(at -4.37 -3.965 180)
			(size 0.3 1.5)
			(layers "F.Cu" "F.Mask" "F.Paste")
			(net 167 "/DDR5 SODIMM/B.CA10")
			(pinfunction "CA10_B")
			(pintype "passive")
		)
		(pad "147" smd rect
			(at -4.62 -11.365 180)
			(size 0.3 1.5)
			(layers "F.Cu" "F.Mask" "F.Paste")
			(net 1 "GND")
			(pinfunction "VSS")
			(pintype "passive")
		)
		(pad "148" smd rect
			(at -4.87 -3.965 180)
			(size 0.3 1.5)
			(layers "F.Cu" "F.Mask" "F.Paste")
			(net 1 "GND")
			(pinfunction "VSS")
			(pintype "passive")
		)
		(pad "149" smd rect
			(at -5.12 -11.365 180)
			(size 0.3 1.5)
			(layers "F.Cu" "F.Mask" "F.Paste")
			(net 168 "/DDR5 SODIMM/B.CA9")
			(pinfunction "CA9_B")
			(pintype "passive")
		)
		(pad "150" smd rect
			(at -5.37 -3.965 180)
			(size 0.3 1.5)
			(layers "F.Cu" "F.Mask" "F.Paste")
			(net 169 "/DDR5 SODIMM/B.CA8")
			(pinfunction "CA8_B")
			(pintype "passive")
		)
		(pad "151" smd rect
			(at -5.62 -11.365 180)
			(size 0.3 1.5)
			(layers "F.Cu" "F.Mask" "F.Paste")
			(net 170 "/DDR5 SODIMM/B.CA7")
			(pinfunction "CA7_B")
			(pintype "passive")
		)
		(pad "152" smd rect
			(at -5.87 -3.965 180)
			(size 0.3 1.5)
			(layers "F.Cu" "F.Mask" "F.Paste")
			(net 174 "/DDR5 SODIMM/B.CA6")
			(pinfunction "CA6_B")
			(pintype "passive")
		)
		(pad "153" smd rect
			(at -6.12 -11.365 180)
			(size 0.3 1.5)
			(layers "F.Cu" "F.Mask" "F.Paste")
			(net 1 "GND")
			(pinfunction "VSS")
			(pintype "passive")
		)
		(pad "154" smd rect
			(at -6.37 -3.965 180)
			(size 0.3 1.5)
			(layers "F.Cu" "F.Mask" "F.Paste")
			(net 1 "GND")
			(pinfunction "VSS")
			(pintype "passive")
		)
		(pad "155" smd rect
			(at -6.62 -11.365 180)
			(size 0.3 1.5)
			(layers "F.Cu" "F.Mask" "F.Paste")
			(net 176 "/DDR5 SODIMM/B.CA5")
			(pinfunction "CA5_B")
			(pintype "passive")
		)
		(pad "156" smd rect
			(at -6.87 -3.965 180)
			(size 0.3 1.5)
			(layers "F.Cu" "F.Mask" "F.Paste")
			(net 177 "/DDR5 SODIMM/B.CA4")
			(pinfunction "CA4_B")
			(pintype "passive")
		)
		(pad "157" smd rect
			(at -7.12 -11.365 180)
			(size 0.3 1.5)
			(layers "F.Cu" "F.Mask" "F.Paste")
			(net 178 "/DDR5 SODIMM/B.CA3")
			(pinfunction "CA3_B")
			(pintype "passive")
		)
		(pad "158" smd rect
			(at -7.37 -3.965 180)
			(size 0.3 1.5)
			(layers "F.Cu" "F.Mask" "F.Paste")
			(net 179 "/DDR5 SODIMM/B.CA2")
			(pinfunction "CA2_B")
			(pintype "passive")
		)
		(pad "159" smd rect
			(at -7.62 -11.365 180)
			(size 0.3 1.5)
			(layers "F.Cu" "F.Mask" "F.Paste")
			(net 1 "GND")
			(pinfunction "VSS")
			(pintype "passive")
		)
		(pad "160" smd rect
			(at -7.87 -3.965 180)
			(size 0.3 1.5)
			(layers "F.Cu" "F.Mask" "F.Paste")
			(net 1 "GND")
			(pinfunction "VSS")
			(pintype "passive")
		)
		(pad "161" smd rect
			(at -8.12 -11.365 180)
			(size 0.3 1.5)
			(layers "F.Cu" "F.Mask" "F.Paste")
			(net 180 "/DDR5 SODIMM/B.~{CS0}")
			(pinfunction "CS0_B_n")
			(pintype "passive")
		)
		(pad "162" smd rect
			(at -8.37 -3.965 180)
			(size 0.3 1.5)
			(layers "F.Cu" "F.Mask" "F.Paste")
			(net 181 "/DDR5 SODIMM/B.CA1")
			(pinfunction "CA1_B")
			(pintype "passive")
		)
		(pad "163" smd rect
			(at -8.62 -11.365 180)
			(size 0.3 1.5)
			(layers "F.Cu" "F.Mask" "F.Paste")
			(net 182 "/DDR5 SODIMM/Control.~{RESET}")
			(pinfunction "RESET_n")
			(pintype "passive")
		)
		(pad "164" smd rect
			(at -8.87 -3.965 180)
			(size 0.3 1.5)
			(layers "F.Cu" "F.Mask" "F.Paste")
			(net 183 "/DDR5 SODIMM/B.CA0")
			(pinfunction "CA0_B")
			(pintype "passive")
		)
		(pad "165" smd rect
			(at -9.12 -11.365 180)
			(size 0.3 1.5)
			(layers "F.Cu" "F.Mask" "F.Paste")
			(net 184 "/DDR5 SODIMM/B.~{CS1}")
			(pinfunction "CS1_B_N")
			(pintype "passive")
		)
		(pad "166" smd rect
			(at -9.37 -3.965 180)
			(size 0.3 1.5)
			(layers "F.Cu" "F.Mask" "F.Paste")
			(net 1 "GND")
			(pinfunction "VSS")
			(pintype "passive")
		)
		(pad "167" smd rect
			(at -9.62 -11.365 180)
			(size 0.3 1.5)
			(layers "F.Cu" "F.Mask" "F.Paste")
			(net 1 "GND")
			(pinfunction "VSS")
			(pintype "passive")
		)
		(pad "168" smd rect
			(at -9.87 -3.965 180)
			(size 0.3 1.5)
			(layers "F.Cu" "F.Mask" "F.Paste")
			(net 189 "/DDR5 SODIMM/B.CB0")
			(pinfunction "CB0_B")
			(pintype "passive")
		)
		(pad "169" smd rect
			(at -10.12 -11.365 180)
			(size 0.3 1.5)
			(layers "F.Cu" "F.Mask" "F.Paste")
			(net 190 "/DDR5 SODIMM/B.DQS4_N")
			(pinfunction "DQS4_B_c")
			(pintype "passive")
		)
		(pad "170" smd rect
			(at -10.37 -3.965 180)
			(size 0.3 1.5)
			(layers "F.Cu" "F.Mask" "F.Paste")
			(net 1 "GND")
			(pinfunction "VSS")
			(pintype "passive")
		)
	)
)
